(kicad_pcb
	(version 20241229)
	(generator "pcbnew")
	(generator_version "9.0")
	(general
		(thickness 0.761)
		(legacy_teardrops no)
	)
	(paper "A4")
	(title_block
		(title " M.2 to OCuLink adapter")
		(date "2025-07-16")
		(rev "1.0.2")
		(company "Antmicro Ltd")
		(comment 1 "www.antmicro.com")
		(comment 9 "footprints 1-3 of 22")
	)
	(layers
		(0 "F.Cu" signal)
		(4 "In1.Cu" signal)
		(6 "In2.Cu" signal)
		(2 "B.Cu" signal)
		(9 "F.Adhes" user "F.Adhesive")
		(11 "B.Adhes" user "B.Adhesive")
		(13 "F.Paste" user)
		(15 "B.Paste" user)
		(5 "F.SilkS" user "F.Silkscreen")
		(7 "B.SilkS" user "B.Silkscreen")
		(1 "F.Mask" user)
		(3 "B.Mask" user)
		(17 "Dwgs.User" user "User.Drawings")
		(19 "Cmts.User" user "User.Comments")
		(21 "Eco1.User" user "User.Eco1")
		(23 "Eco2.User" user "User.Eco2")
		(25 "Edge.Cuts" user)
		(27 "Margin" user)
		(31 "F.CrtYd" user "F.Courtyard")
		(29 "B.CrtYd" user "B.Courtyard")
		(35 "F.Fab" user)
		(33 "B.Fab" user)
	)
	(footprint "antmicro-footprints:R_0402_1005Metric"
		(layer "F.Cu")
		(at 136.74 121.06 90)
		(descr "Resistor SMD 0402")
		(tags "resistor SMD 0402")
		(property "Reference" "R1"
			(at 0.87 0.41 270)
			(layer "F.SilkS")
			(effects
				(font
					(size 0.7 0.7)
					(thickness 0.15)
				)
				(justify left bottom)
			)
		)
		(property "Value" "R_0R_0402"
			(at -1.011843 1.772047 90)
			(layer "F.Fab")
			(effects
				(font
					(size 0.7 0.7)
					(thickness 0.15)
				)
				(justify left bottom)
			)
		)
		(property "Datasheet" "https://industrial.panasonic.com/cdbs/www-data/pdf/RDA0000/AOA0000C301.pdf"
			(at 0 0 90)
			(layer "F.Fab")
			(hide yes)
			(effects
				(font
					(size 1.27 1.27)
					(thickness 0.15)
				)
			)
		)
		(property "Description" "SMD Chip Resistor, Jumper, 0 ohm, 100 mW, 0402 [1005 Metric], Thick Film, General Purpose"
			(at 0 0 90)
			(layer "F.Fab")
			(hide yes)
			(effects
				(font
					(size 1.27 1.27)
					(thickness 0.15)
				)
			)
		)
		(property "MPN" "ERJ2GE0R00X"
			(at 0 0 90)
			(unlocked yes)
			(layer "F.Fab")
			(hide yes)
			(effects
				(font
					(size 1 1)
					(thickness 0.15)
				)
			)
		)
		(property "Manufacturer" "Panasonic"
			(at 0 0 90)
			(unlocked yes)
			(layer "F.Fab")
			(hide yes)
			(effects
				(font
					(size 1 1)
					(thickness 0.15)
				)
			)
		)
		(property "License" "Apache-2.0"
			(at 0 0 90)
			(unlocked yes)
			(layer "F.Fab")
			(hide yes)
			(effects
				(font
					(size 1 1)
					(thickness 0.15)
				)
			)
		)
		(property "Author" "Antmicro"
			(at 0 0 90)
			(unlocked yes)
			(layer "F.Fab")
			(hide yes)
			(effects
				(font
					(size 1 1)
					(thickness 0.15)
				)
			)
		)
		(property "Val" "0R"
			(at 0 0 90)
			(unlocked yes)
			(layer "F.Fab")
			(hide yes)
			(effects
				(font
					(size 1 1)
					(thickness 0.15)
				)
			)
		)
		(property "Tolerance" ""
			(at 0 0 90)
			(unlocked yes)
			(layer "F.Fab")
			(hide yes)
			(effects
				(font
					(size 1 1)
					(thickness 0.15)
				)
			)
		)
		(property "Current" "1A"
			(at 0 0 90)
			(unlocked yes)
			(layer "F.Fab")
			(hide yes)
			(effects
				(font
					(size 1 1)
					(thickness 0.15)
				)
			)
		)
		(sheetname "/")
		(sheetfile "antmicro-m2-oculink-adapter-hw.kicad_sch")
		(attr smd)
		(fp_rect
			(start -0.925 -0.47)
			(end 0.925 0.47)
			(stroke
				(width 0.05)
				(type default)
			)
			(fill no)
			(layer "F.CrtYd")
		)
		(fp_rect
			(start -0.5 -0.25)
			(end 0.5 0.25)
			(stroke
				(width 0.15)
				(type solid)
			)
			(fill no)
			(layer "F.Fab")
		)
		(fp_text user "Author: Antmicro"
			(at -0.95 4.169 90)
			(layer "F.Fab")
			(effects
				(font
					(size 0.7 0.7)
					(thickness 0.15)
				)
				(justify left bottom)
			)
		)
		(fp_text user "License: Apache-2.0"
			(at -0.95 5.169 90)
			(layer "F.Fab")
			(effects
				(font
					(size 0.7 0.7)
					(thickness 0.15)
				)
				(justify left bottom)
			)
		)
		(fp_text user "${REFERENCE}"
			(at -0.95 3.168 90)
			(layer "F.Fab")
			(effects
				(font
					(size 0.7 0.7)
					(thickness 0.15)
				)
				(justify left bottom)
			)
		)
		(pad "1" smd roundrect
			(at -0.48 0 90)
			(size 0.59 0.64)
			(layers "F.Cu" "F.Mask" "F.Paste")
			(roundrect_rratio 0.25)
			(net 41 "Net-(J1-CLKREQ#)")
			(pintype "passive")
		)
		(pad "2" smd roundrect
			(at 0.48 0 90)
			(size 0.59 0.64)
			(layers "F.Cu" "F.Mask" "F.Paste")
			(roundrect_rratio 0.25)
			(net 1 "GND")
			(pintype "passive")
		)
	)
	(footprint "antmicro-footprints:R_0402_1005Metric"
		(layer "F.Cu")
		(at 140.1 89.66 180)
		(descr "Resistor SMD 0402")
		(tags "resistor SMD 0402")
		(property "Reference" "R11"
			(at -3 0.38 0)
			(layer "F.SilkS")
			(effects
				(font
					(size 0.7 0.7)
					(thickness 0.15)
				)
				(justify right top)
			)
		)
		(property "Value" "R_0R_0402"
			(at -1.011843 1.772047 0)
			(layer "F.Fab")
			(effects
				(font
					(size 0.7 0.7)
					(thickness 0.15)
				)
				(justify right top)
			)
		)
		(property "Datasheet" "https://industrial.panasonic.com/cdbs/www-data/pdf/RDA0000/AOA0000C301.pdf"
			(at 0 0 0)
			(layer "F.Fab")
			(hide yes)
			(effects
				(font
					(size 1.27 1.27)
					(thickness 0.15)
				)
			)
		)
		(property "Description" "SMD Chip Resistor, Jumper, 0 ohm, 100 mW, 0402 [1005 Metric], Thick Film, General Purpose"
			(at 0 0 0)
			(layer "F.Fab")
			(hide yes)
			(effects
				(font
					(size 1.27 1.27)
					(thickness 0.15)
				)
			)
		)
		(property "MPN" "ERJ2GE0R00X"
			(at 0 0 180)
			(unlocked yes)
			(layer "F.Fab")
			(hide yes)
			(effects
				(font
					(size 1 1)
					(thickness 0.15)
				)
			)
		)
		(property "Manufacturer" "Panasonic"
			(at 0 0 180)
			(unlocked yes)
			(layer "F.Fab")
			(hide yes)
			(effects
				(font
					(size 1 1)
					(thickness 0.15)
				)
			)
		)
		(property "License" "Apache-2.0"
			(at 0 0 180)
			(unlocked yes)
			(layer "F.Fab")
			(hide yes)
			(effects
				(font
					(size 1 1)
					(thickness 0.15)
				)
			)
		)
		(property "Author" "Antmicro"
			(at 0 0 180)
			(unlocked yes)
			(layer "F.Fab")
			(hide yes)
			(effects
				(font
					(size 1 1)
					(thickness 0.15)
				)
			)
		)
		(property "Val" "0R"
			(at 0 0 180)
			(unlocked yes)
			(layer "F.Fab")
			(hide yes)
			(effects
				(font
					(size 1 1)
					(thickness 0.15)
				)
			)
		)
		(property "Tolerance" ""
			(at 0 0 180)
			(unlocked yes)
			(layer "F.Fab")
			(hide yes)
			(effects
				(font
					(size 1 1)
					(thickness 0.15)
				)
			)
		)
		(property "Current" "1A"
			(at 0 0 180)
			(unlocked yes)
			(layer "F.Fab")
			(hide yes)
			(effects
				(font
					(size 1 1)
					(thickness 0.15)
				)
			)
		)
		(sheetname "/")
		(sheetfile "antmicro-m2-oculink-adapter-hw.kicad_sch")
		(attr smd)
		(fp_rect
			(start -0.925 -0.47)
			(end 0.925 0.47)
			(stroke
				(width 0.05)
				(type default)
			)
			(fill no)
			(layer "F.CrtYd")
		)
		(fp_rect
			(start -0.5 -0.25)
			(end 0.5 0.25)
			(stroke
				(width 0.15)
				(type solid)
			)
			(fill no)
			(layer "F.Fab")
		)
		(fp_text user "License: Apache-2.0"
			(at -0.95 5.169 0)
			(layer "F.Fab")
			(effects
				(font
					(size 0.7 0.7)
					(thickness 0.15)
				)
				(justify right top)
			)
		)
		(fp_text user "${REFERENCE}"
			(at -0.95 3.168 0)
			(layer "F.Fab")
			(effects
				(font
					(size 0.7 0.7)
					(thickness 0.15)
				)
				(justify right top)
			)
		)
		(fp_text user "Author: Antmicro"
			(at -0.95 4.169 0)
			(layer "F.Fab")
			(effects
				(font
					(size 0.7 0.7)
					(thickness 0.15)
				)
				(justify right top)
			)
		)
		(pad "1" smd roundrect
			(at -0.48 0 180)
			(size 0.59 0.64)
			(layers "F.Cu" "F.Mask" "F.Paste")
			(roundrect_rratio 0.25)
			(net 24 "/~{WAKEC}")
			(pintype "passive")
			(teardrops
				(best_length_ratio 0.5)
				(max_length 1)
				(best_width_ratio 1)
				(max_width 2)
				(curved_edges yes)
				(filter_ratio 0.9)
				(enabled no)
				(allow_two_segments yes)
				(prefer_zone_connections no)
			)
		)
		(pad "2" smd roundrect
			(at 0.48 0 180)
			(size 0.59 0.64)
			(layers "F.Cu" "F.Mask" "F.Paste")
			(roundrect_rratio 0.25)
			(net 37 "/~{WAKE}")
			(pintype "passive")
			(teardrops
				(best_length_ratio 0.5)
				(max_length 1)
				(best_width_ratio 1)
				(max_width 2)
				(curved_edges yes)
				(filter_ratio 0.9)
				(enabled no)
				(allow_two_segments yes)
				(prefer_zone_connections no)
			)
		)
	)
	(footprint "antmicro-footprints:C_0402_1005Metric"
		(layer "F.Cu")
		(at 136.71 124.19 -90)
		(descr "Capacitor SMD 0402")
		(tags "capacitor SMD 0402")
		(property "Reference" "C2"
			(at -2.32 0.39 90)
			(layer "F.SilkS")
			(effects
				(font
					(size 0.7 0.7)
					(thickness 0.15)
				)
				(justify right top)
			)
		)
		(property "Value" "C_100n_16V_X7R_0402"
			(at -1.022927 2.155213 90)
			(layer "F.Fab")
			(effects
				(font
					(size 0.7 0.7)
					(thickness 0.15)
				)
				(justify right top)
			)
		)
		(property "Datasheet" "https://www.kemet.com/en/us/capacitors/product/C0402C104J4RAC7411.html"
			(at 0 0 90)
			(layer "F.Fab")
			(hide yes)
			(effects
				(font
					(size 1.27 1.27)
					(thickness 0.15)
				)
			)
		)
		(property "Description" "SMD Multilayer Ceramic Capacitor, 100nF, 50V, 0402, ±5%, X7R"
			(at 0 0 90)
			(layer "F.Fab")
			(hide yes)
			(effects
				(font
					(size 1.27 1.27)
					(thickness 0.15)
				)
			)
		)
		(property "MPN" "C0402C104J4RAC7411"
			(at 0 0 270)
			(unlocked yes)
			(layer "F.Fab")
			(hide yes)
			(effects
				(font
					(size 1 1)
					(thickness 0.15)
				)
			)
		)
		(property "Val" "100n"
			(at 0 0 270)
			(unlocked yes)
			(layer "F.Fab")
			(hide yes)
			(effects
				(font
					(size 1 1)
					(thickness 0.15)
				)
			)
		)
		(property "Voltage" "16V"
			(at 0 0 270)
			(unlocked yes)
			(layer "F.Fab")
			(hide yes)
			(effects
				(font
					(size 1 1)
					(thickness 0.15)
				)
			)
		)
		(property "Dielectric" "X7R"
			(at 0 0 270)
			(unlocked yes)
			(layer "F.Fab")
			(hide yes)
			(effects
				(font
					(size 1 1)
					(thickness 0.15)
				)
			)
		)
		(property "Manufacturer" "KEMET"
			(at 0 0 270)
			(unlocked yes)
			(layer "F.Fab")
			(hide yes)
			(effects
				(font
					(size 1 1)
					(thickness 0.15)
				)
			)
		)
		(property "License" "Apache-2.0"
			(at 0 0 270)
			(unlocked yes)
			(layer "F.Fab")
			(hide yes)
			(effects
				(font
					(size 1 1)
					(thickness 0.15)
				)
			)
		)
		(property "Author" "Antmicro"
			(at 0 0 270)
			(unlocked yes)
			(layer "F.Fab")
			(hide yes)
			(effects
				(font
					(size 1 1)
					(thickness 0.15)
				)
			)
		)
		(sheetname "/")
		(sheetfile "antmicro-m2-oculink-adapter-hw.kicad_sch")
		(attr smd)
		(fp_rect
			(start -0.925 -0.47)
			(end 0.925 0.47)
			(stroke
				(width 0.05)
				(type default)
			)
			(fill no)
			(layer "F.CrtYd")
		)
		(fp_line
			(start -0.494 0.248)
			(end -0.494 -0.25)
			(stroke
				(width 0.15)
				(type solid)
			)
			(layer "F.Fab")
		)
		(fp_line
			(start 0.504 0.248)
			(end -0.494 0.248)
			(stroke
				(width 0.15)
				(type solid)
			)
			(layer "F.Fab")
		)
		(fp_line
			(start -0.494 -0.25)
			(end 0.504 -0.25)
			(stroke
				(width 0.15)
				(type solid)
			)
			(layer "F.Fab")
		)
		(fp_line
			(start 0.504 -0.25)
			(end 0.504 0.248)
			(stroke
				(width 0.15)
				(type solid)
			)
			(layer "F.Fab")
		)
		(fp_text user "License: Apache-2.0"
			(at -0.939 5.799 90)
			(layer "F.Fab")
			(effects
				(font
					(size 0.7 0.7)
					(thickness 0.15)
				)
				(justify right top)
			)
		)
		(fp_text user "${REFERENCE}"
			(at -0.939 4.599 90)
			(layer "F.Fab")
			(effects
				(font
					(size 0.7 0.7)
					(thickness 0.15)
				)
				(justify right top)
			)
		)
		(fp_text user "Author: Antmicro"
			(at -0.939 3.399 90)
			(layer "F.Fab")
			(effects
				(font
					(size 0.7 0.7)
					(thickness 0.15)
				)
				(justify right top)
			)
		)
		(pad "1" smd roundrect
			(at -0.48 0 270)
			(size 0.59 0.64)
			(layers "F.Cu" "F.Mask" "F.Paste")
			(roundrect_rratio 0.25)
			(net 1 "GND")
			(pintype "passive")
		)
		(pad "2" smd roundrect
			(at 0.48 0 270)
			(size 0.59 0.64)
			(layers "F.Cu" "F.Mask" "F.Paste")
			(roundrect_rratio 0.25)
			(net 56 "Net-(C1-Pad2)")
			(pintype "passive")
		)
	)
)
